# TIMECARD (Time Appliance Project (Time Card)) — schematic netlist excerpt (pin names and nets, part order shuffled) for the footprints in the layout excerpt that follows; sources: Cadence DE-HDL packaged netlist, KiCad conversion of R4006-B0001-02_R01.brd

C127  CAPACITOR  0.1UF 10V 10%  pkg SMC_0402R_H022  page 14 : \1\ = XP2R5V_FPGA ; \2\ = SG
C135  CAPACITOR  0.1UF 10V 10%  pkg SMC_0402R_H022  page 14 : \1\ = XP2R5V_FPGA ; \2\ = SG

(kicad_pcb
	(version 20260206)
	(generator "pcbnew")
	(generator_version "10.0")
	(general
		(thickness 1.6)
		(legacy_teardrops no)
	)
	(paper "A4")
	(title_block
		(title "timecard-production-celestica-r4006 — R4006-B0001-02_R01.brd")
		(comment 1 "Time Appliance Project (Time Card) / footprints 810-811 of 1113")
	)
	(layers
		(0 "F.Cu" signal "TOP")
		(4 "In1.Cu" signal "L02_GND1")
		(6 "In2.Cu" signal "L03_SIG1")
		(8 "In3.Cu" signal "L04_GND2")
		(10 "In4.Cu" signal "L05_VCC1")
		(12 "In5.Cu" signal "L06_VCC2")
		(14 "In6.Cu" signal "L07_GND3")
		(16 "In7.Cu" signal "L08_SIG2")
		(18 "In8.Cu" signal "L09_GND4")
		(2 "B.Cu" signal "BOTTOM")
		(9 "F.Adhes" user "F.Adhesive")
		(11 "B.Adhes" user "B.Adhesive")
		(13 "F.Paste" user "Package Geometry/Pastemask Top")
		(15 "B.Paste" user "Package Geometry/Pastemask Bottom")
		(5 "F.SilkS" user "Ref Des/Silkscreen Top")
		(7 "B.SilkS" user "Ref Des/Silkscreen Bottom")
		(1 "F.Mask" user "Board Geometry/Soldermask Top")
		(3 "B.Mask" user "Board Geometry/Soldermask Bottom")
		(17 "Dwgs.User" user "User.Drawings")
		(19 "Cmts.User" user "User.Comments")
		(21 "Eco1.User" user "User.Eco1")
		(23 "Eco2.User" user "User.Eco2")
		(25 "Edge.Cuts" user "Board Geometry/Outline")
		(27 "Margin" user)
		(31 "F.CrtYd" user "Package Geometry/Place Bound Top")
		(29 "B.CrtYd" user "Package Geometry/Place Bound Bottom")
		(35 "F.Fab" user "Ref Des/Assembly Top")
		(33 "B.Fab" user "Ref Des/Assembly Bottom")
	)
	(footprint ""
		(layer "B.Cu")
		(at 116.346986 -35.82289)
		(property "Reference" "C127"
			(at 0.239014 -0.97536 0)
			(unlocked yes)
			(layer "B.SilkS")
			(effects
				(font
					(size 0.635 0.4064)
					(thickness 0.1524)
				)
				(justify mirror)
			)
		)
		(property "Value" "VAL*"
			(at 0 3.718306 0)
			(unlocked yes)
			(layer "B.Fab")
			(hide yes)
			(effects
				(font
					(size 0.7874 0.5842)
					(thickness 0.127)
				)
				(justify mirror)
			)
		)
		(property "Device Type" "CAPACITOR-G105-0B104-CK,0.1UF,A"
			(at 0 1.432306 0)
			(unlocked yes)
			(layer "B.Fab")
			(hide yes)
			(effects
				(font
					(size 0.7874 0.5842)
					(thickness 0.127)
				)
				(justify mirror)
			)
		)
		(property "User Part Number" "PARTNUM*"
			(at 0 2.575306 0)
			(unlocked yes)
			(layer "Cmts.User")
			(hide yes)
			(effects
				(font
					(size 0.7874 0.5842)
					(thickness 0.127)
				)
				(justify mirror)
			)
		)
		(property "Tolerance" "TOL*"
			(at 0 4.861306 0)
			(unlocked yes)
			(layer "Cmts.User")
			(hide yes)
			(effects
				(font
					(size 0.7874 0.5842)
					(thickness 0.127)
				)
				(justify mirror)
			)
		)
		(duplicate_pad_numbers_are_jumpers no)
		(fp_line
			(start -0.970026 -0.4699)
			(end -0.970026 0.4699)
			(stroke
				(width 0.1)
				(type default)
			)
			(layer "B.SilkS")
		)
		(fp_line
			(start -0.970026 0.4699)
			(end 0.970026 0.4699)
			(stroke
				(width 0.1)
				(type default)
			)
			(layer "B.SilkS")
		)
		(fp_line
			(start 0.970026 -0.4699)
			(end -0.970026 -0.4699)
			(stroke
				(width 0.1)
				(type default)
			)
			(layer "B.SilkS")
		)
		(fp_line
			(start 0.970026 0.4699)
			(end 0.970026 -0.4699)
			(stroke
				(width 0.1)
				(type default)
			)
			(layer "B.SilkS")
		)
		(fp_poly
			(pts
				(xy 0.970026 0.4699) (xy -0.970026 0.4699) (xy -0.970026 -0.4699) (xy 0.970026 -0.4699)
			)
			(stroke
				(width 0)
				(type default)
			)
			(fill no)
			(layer "B.CrtYd")
		)
		(fp_line
			(start -0.508 -0.3048)
			(end -0.508 0.3048)
			(stroke
				(width 0.1)
				(type default)
			)
			(layer "B.Fab")
		)
		(fp_line
			(start -0.508 0.3048)
			(end 0.508 0.3048)
			(stroke
				(width 0.1)
				(type default)
			)
			(layer "B.Fab")
		)
		(fp_line
			(start 0.508 -0.3048)
			(end -0.508 -0.3048)
			(stroke
				(width 0.1)
				(type default)
			)
			(layer "B.Fab")
		)
		(fp_line
			(start 0.508 0.3048)
			(end 0.508 -0.3048)
			(stroke
				(width 0.1)
				(type default)
			)
			(layer "B.Fab")
		)
		(pad "1" smd circle
			(at 0.500126 0 180)
			(size 0.635 0.635)
			(layers "B.Cu" "B.Mask" "B.Paste")
			(net "XP2R5V_FPGA")
		)
		(pad "2" smd circle
			(at -0.500126 0 180)
			(size 0.635 0.635)
			(layers "B.Cu" "B.Mask" "B.Paste")
			(net "SG")
		)
	)
	(footprint ""
		(layer "B.Cu")
		(at 112.84712 -36.323016 90)
		(property "Reference" "C135"
			(at -2.287016 -0.10287 270)
			(unlocked yes)
			(layer "B.SilkS")
			(effects
				(font
					(size 0.635 0.4064)
					(thickness 0.1524)
				)
				(justify mirror)
			)
		)
		(property "Value" "VAL*"
			(at 0 3.718306 90)
			(unlocked yes)
			(layer "B.Fab")
			(hide yes)
			(effects
				(font
					(size 0.7874 0.5842)
					(thickness 0.127)
				)
				(justify mirror)
			)
		)
		(property "Tolerance" "TOL*"
			(at 0 4.861306 90)
			(unlocked yes)
			(layer "Cmts.User")
			(hide yes)
			(effects
				(font
					(size 0.7874 0.5842)
					(thickness 0.127)
				)
				(justify mirror)
			)
		)
		(property "User Part Number" "PARTNUM*"
			(at 0 2.575306 90)
			(unlocked yes)
			(layer "Cmts.User")
			(hide yes)
			(effects
				(font
					(size 0.7874 0.5842)
					(thickness 0.127)
				)
				(justify mirror)
			)
		)
		(property "Device Type" "CAPACITOR-G105-0B104-CK,0.1UF,A"
			(at 0 1.432306 90)
			(unlocked yes)
			(layer "B.Fab")
			(hide yes)
			(effects
				(font
					(size 0.7874 0.5842)
					(thickness 0.127)
				)
				(justify mirror)
			)
		)
		(duplicate_pad_numbers_are_jumpers no)
		(fp_line
			(start 0.970026 -0.4699)
			(end -0.970026 -0.4699)
			(stroke
				(width 0.1)
				(type default)
			)
			(layer "B.SilkS")
		)
		(fp_line
			(start -0.970026 -0.4699)
			(end -0.970026 0.4699)
			(stroke
				(width 0.1)
				(type default)
			)
			(layer "B.SilkS")
		)
		(fp_line
			(start 0.970026 0.4699)
			(end 0.970026 -0.4699)
			(stroke
				(width 0.1)
				(type default)
			)
			(layer "B.SilkS")
		)
		(fp_line
			(start -0.970026 0.4699)
			(end 0.970026 0.4699)
			(stroke
				(width 0.1)
				(type default)
			)
			(layer "B.SilkS")
		)
		(fp_poly
			(pts
				(xy 0.970026 0.4699) (xy -0.970026 0.4699) (xy -0.970026 -0.4699) (xy 0.970026 -0.4699)
			)
			(stroke
				(width 0)
				(type default)
			)
			(fill no)
			(layer "B.CrtYd")
		)
		(fp_line
			(start 0.508 -0.3048)
			(end -0.508 -0.3048)
			(stroke
				(width 0.1)
				(type default)
			)
			(layer "B.Fab")
		)
		(fp_line
			(start -0.508 -0.3048)
			(end -0.508 0.3048)
			(stroke
				(width 0.1)
				(type default)
			)
			(layer "B.Fab")
		)
		(fp_line
			(start 0.508 0.3048)
			(end 0.508 -0.3048)
			(stroke
				(width 0.1)
				(type default)
			)
			(layer "B.Fab")
		)
		(fp_line
			(start -0.508 0.3048)
			(end 0.508 0.3048)
			(stroke
				(width 0.1)
				(type default)
			)
			(layer "B.Fab")
		)
		(pad "1" smd circle
			(at 0.500126 0 270)
			(size 0.635 0.635)
			(layers "B.Cu" "B.Mask" "B.Paste")
			(net "XP2R5V_FPGA")
		)
		(pad "2" smd circle
			(at -0.500126 0 270)
			(size 0.635 0.635)
			(layers "B.Cu" "B.Mask" "B.Paste")
			(net "SG")
		)
	)
)
